# S9S_MB_2U (Grand Teton) — schematic netlist excerpt (pin names and nets, part order shuffled) for the footprints in the layout excerpt that follows; sources: Cadence DE-HDL packaged netlist, KiCad conversion of 03242023_DA0F0TMBIJ0_F0T_Motherboard_J_brd_V01_OCP.brd

H115  GND_HOLE  EMPTY  pkg TH  page 311
  GND2  = GND
  GND3  = GND
  GND4  = GND
  GND5  = GND
  GND6  = GND
  GND7  = GND
  GND8  = GND
  GND9  = GND

(kicad_pcb
	(version 20260206)
	(generator "pcbnew")
	(generator_version "10.0")
	(general
		(thickness 1.6)
		(legacy_teardrops no)
	)
	(paper "A4")
	(title_block
		(title "03242023_DA0F0TMBIJ0_F0T_Motherboard_J_brd_V01_OCP.brd")
		(comment 1 "Grand Teton / footprints 690-690 of 6105")
	)
	(layers
		(0 "F.Cu" signal "TOP")
		(4 "In1.Cu" signal "GND")
		(6 "In2.Cu" signal "IN1")
		(8 "In3.Cu" signal "GND1")
		(10 "In4.Cu" signal "IN2")
		(12 "In5.Cu" signal "GND2")
		(14 "In6.Cu" signal "IN3")
		(16 "In7.Cu" signal "GND3")
		(18 "In8.Cu" signal "VCC")
		(20 "In9.Cu" signal "VCC1")
		(22 "In10.Cu" signal "GND4")
		(24 "In11.Cu" signal "IN4")
		(26 "In12.Cu" signal "GND5")
		(28 "In13.Cu" signal "IN5")
		(30 "In14.Cu" signal "GND6")
		(32 "In15.Cu" signal "IN6")
		(34 "In16.Cu" signal "GND7")
		(2 "B.Cu" signal "BOTTOM")
		(9 "F.Adhes" user "F.Adhesive")
		(11 "B.Adhes" user "B.Adhesive")
		(13 "F.Paste" user "Package Geometry/Pastemask Top")
		(15 "B.Paste" user "Package Geometry/Pastemask Bottom")
		(5 "F.SilkS" user "Ref Des/Silkscreen Top")
		(7 "B.SilkS" user "Ref Des/Silkscreen Bottom")
		(1 "F.Mask" user "Board Geometry/Soldermask Top")
		(3 "B.Mask" user "Board Geometry/Soldermask Bottom")
		(17 "Dwgs.User" user "User.Drawings")
		(19 "Cmts.User" user "User.Comments")
		(21 "Eco1.User" user "User.Eco1")
		(23 "Eco2.User" user "User.Eco2")
		(25 "Edge.Cuts" user "Board Geometry/Outline")
		(27 "Margin" user)
		(31 "F.CrtYd" user "Package Geometry/Place Bound Top")
		(29 "B.CrtYd" user "Package Geometry/Place Bound Bottom")
		(35 "F.Fab" user "Ref Des/Assembly Top")
		(33 "B.Fab" user "Ref Des/Assembly Bottom")
	)
	(footprint ""
		(layer "F.Cu")
		(at 235.899706 -81.699862 180)
		(property "Reference" "H115"
			(at -3.231388 -9.86282 0)
			(unlocked yes)
			(layer "F.SilkS")
			(effects
				(font
					(size 0.7874 0.5842)
					(thickness 0.1524)
				)
				(justify left)
			)
		)
		(property "Value" ""
			(at 0 0 180)
			(layer "F.Fab")
			(effects
				(font
					(size 1.27 1.27)
				)
			)
		)
		(duplicate_pad_numbers_are_jumpers no)
		(fp_circle
			(center 0 0)
			(end -7.999984 0)
			(stroke
				(width 0.1524)
				(type default)
			)
			(fill no)
			(layer "F.SilkS")
		)
		(fp_arc
			(start 1.378458 7.88035)
			(mid -5.146459 6.124845)
			(end -7.999984 0)
			(stroke
				(width 0.1524)
				(type default)
			)
			(layer "B.SilkS")
		)
		(fp_arc
			(start -0.846328 -7.955026)
			(mid 6.678862 -4.403794)
			(end 6.978396 3.911854)
			(stroke
				(width 0.1524)
				(type default)
			)
			(layer "B.SilkS")
		)
		(fp_arc
			(start -7.999984 0)
			(mid -7.68431 -2.225377)
			(end -6.761988 -4.275074)
			(stroke
				(width 0.1524)
				(type default)
			)
			(layer "B.SilkS")
		)
		(fp_circle
			(center 0 0)
			(end -7.999984 0)
			(stroke
				(width 0.1)
				(type default)
			)
			(fill no)
			(layer "B.Fab")
		)
		(fp_circle
			(center 0 0)
			(end -7.999984 0)
			(stroke
				(width 0.1)
				(type default)
			)
			(fill no)
			(layer "F.Fab")
		)
		(pad "" np_thru_hole oval
			(at 0 0 90)
			(size 5.08 6.477)
			(drill oval 5.08 6.477)
			(layers "*.Cu" "*.Mask")
			(clearance 0.381)
			(thermal_gap 0.381)
		)
		(pad "2" thru_hole circle
			(at 4.38023 0 180)
			(size 0.762 0.762)
			(drill 0.5588)
			(layers "*.Cu" "*.Mask")
			(remove_unused_layers no)
			(net "GND")
			(clearance 0.1524)
			(thermal_gap 0.1524)
		)
		(pad "3" thru_hole circle
			(at 3.097276 -3.097276 180)
			(size 0.762 0.762)
			(drill 0.5588)
			(layers "*.Cu" "*.Mask")
			(remove_unused_layers no)
			(net "GND")
			(clearance 0.1524)
			(thermal_gap 0.1524)
		)
		(pad "4" thru_hole circle
			(at 0 -4.38023 180)
			(size 0.762 0.762)
			(drill 0.5588)
			(layers "*.Cu" "*.Mask")
			(remove_unused_layers no)
			(net "GND")
			(clearance 0.1524)
			(thermal_gap 0.1524)
		)
		(pad "5" thru_hole circle
			(at -3.097276 -3.097276 180)
			(size 0.762 0.762)
			(drill 0.5588)
			(layers "*.Cu" "*.Mask")
			(remove_unused_layers no)
			(net "GND")
			(clearance 0.1524)
			(thermal_gap 0.1524)
		)
		(pad "6" thru_hole circle
			(at -4.38023 0 180)
			(size 0.762 0.762)
			(drill 0.5588)
			(layers "*.Cu" "*.Mask")
			(remove_unused_layers no)
			(net "GND")
			(clearance 0.1524)
			(thermal_gap 0.1524)
		)
		(pad "7" thru_hole circle
			(at -3.097276 3.097276 180)
			(size 0.762 0.762)
			(drill 0.5588)
			(layers "*.Cu" "*.Mask")
			(remove_unused_layers no)
			(net "GND")
			(clearance 0.1524)
			(thermal_gap 0.1524)
		)
		(pad "8" thru_hole circle
			(at 0 4.38023 180)
			(size 0.762 0.762)
			(drill 0.5588)
			(layers "*.Cu" "*.Mask")
			(remove_unused_layers no)
			(net "GND")
			(clearance 0.1524)
			(thermal_gap 0.1524)
		)
		(pad "9" thru_hole circle
			(at 3.097276 3.097276 180)
			(size 0.762 0.762)
			(drill 0.5588)
			(layers "*.Cu" "*.Mask")
			(remove_unused_layers no)
			(net "GND")
			(clearance 0.1524)
			(thermal_gap 0.1524)
		)
		(zone
			(layer "F.Cu")
			(hatch none 0.5)
			(connect_pads
				(clearance 0)
			)
			(min_thickness 0.25)
			(keepout
				(tracks not_allowed)
				(vias allowed)
				(pads allowed)
				(copperpour not_allowed)
				(footprints allowed)
			)
			(placement
				(enabled no)
				(sheetname "")
			)
			(fill
				(thermal_gap 0.5)
				(thermal_bridge_width 0.5)
				(island_removal_mode 0)
			)
			(polygon
				(pts
					(arc
						(start 230.391716 -81.699862)
						(mid 232.004969 -85.594599)
						(end 235.899706 -87.207852)
					)
					(arc
						(start 235.899706 -86.725252)
						(mid 230.874316 -81.699862)
						(end 235.899706 -76.674472)
					)
					(arc
						(start 235.899706 -76.191872)
						(mid 232.004969 -77.805125)
						(end 230.391716 -81.699862)
					)
				)
			)
		)
		(zone
			(layer "F.Cu")
			(hatch none 0.5)
			(connect_pads
				(clearance 0)
			)
			(min_thickness 0.25)
			(keepout
				(tracks not_allowed)
				(vias allowed)
				(pads allowed)
				(copperpour not_allowed)
				(footprints allowed)
			)
			(placement
				(enabled no)
				(sheetname "")
			)
			(fill
				(thermal_gap 0.5)
				(thermal_bridge_width 0.5)
				(island_removal_mode 0)
			)
			(polygon
				(pts
					(arc
						(start 241.407696 -81.699862)
						(mid 239.794443 -85.594599)
						(end 235.899706 -87.207852)
					)
					(arc
						(start 235.899706 -86.725252)
						(mid 240.925096 -81.699862)
						(end 235.899706 -76.674472)
					)
					(arc
						(start 235.899706 -76.191872)
						(mid 239.794443 -77.805125)
						(end 241.407696 -81.699862)
					)
				)
			)
		)
		(zone
			(layers "F.Cu" "B.Cu" "In1.Cu" "In2.Cu" "In3.Cu" "In4.Cu" "In5.Cu" "In6.Cu"
				"In7.Cu" "In8.Cu" "In9.Cu" "In10.Cu" "In11.Cu" "In12.Cu" "In13.Cu" "In14.Cu"
				"In15.Cu" "In16.Cu"
			)
			(hatch none 0.5)
			(connect_pads
				(clearance 0)
			)
			(min_thickness 0.25)
			(keepout
				(tracks not_allowed)
				(vias allowed)
				(pads allowed)
				(copperpour not_allowed)
				(footprints allowed)
			)
			(placement
				(enabled no)
				(sheetname "")
			)
			(fill
				(thermal_gap 0.5)
				(thermal_bridge_width 0.5)
				(island_removal_mode 0)
			)
			(polygon
				(pts
					(arc
						(start 233.715306 -78.641956)
						(mid 235.899706 -85.457839)
						(end 238.084106 -78.641956)
					)
				)
			)
		)
		(zone
			(layer "B.Cu")
			(hatch none 0.5)
			(connect_pads
				(clearance 0)
			)
			(min_thickness 0.25)
			(keepout
				(tracks not_allowed)
				(vias allowed)
				(pads allowed)
				(copperpour not_allowed)
				(footprints allowed)
			)
			(placement
				(enabled no)
				(sheetname "")
			)
			(fill
				(thermal_gap 0.5)
				(thermal_bridge_width 0.5)
				(island_removal_mode 0)
			)
			(polygon
				(pts
					(arc
						(start 235.899706 -89.699846)
						(mid 227.899722 -81.699862)
						(end 235.899706 -73.699878)
					)
					(arc
						(start 235.899706 -76.445872)
						(mid 232.184574 -77.98473)
						(end 230.645716 -81.699862)
					)
					(arc
						(start 230.645716 -81.699862)
						(mid 232.184574 -85.414994)
						(end 235.899706 -86.953852)
					)
				)
			)
		)
		(zone
			(layer "B.Cu")
			(hatch none 0.5)
			(connect_pads
				(clearance 0)
			)
			(min_thickness 0.25)
			(keepout
				(tracks not_allowed)
				(vias allowed)
				(pads allowed)
				(copperpour not_allowed)
				(footprints allowed)
			)
			(placement
				(enabled no)
				(sheetname "")
			)
			(fill
				(thermal_gap 0.5)
				(thermal_bridge_width 0.5)
				(island_removal_mode 0)
			)
			(polygon
				(pts
					(arc
						(start 235.899706 -89.699846)
						(mid 243.89969 -81.699862)
						(end 235.899706 -73.699878)
					)
					(arc
						(start 235.899706 -76.445872)
						(mid 239.614838 -77.98473)
						(end 241.153696 -81.699862)
					)
					(arc
						(start 241.153696 -81.699862)
						(mid 239.614838 -85.414994)
						(end 235.899706 -86.953852)
					)
				)
			)
		)
	)
)
